(kicad_pcb
	(version 20260206)
	(generator "pcbnew")
	(generator_version "10.0")
	(general
		(thickness 1.6)
		(legacy_teardrops no)
	)
	(paper "A4")
	(title_block
		(title "Wiwynn_Tioga_Pass_MB.brd")
		(comment 1 "Tioga Pass / footprint 2445 of 4770 (J9M1), pads 244-291 of 291")
	)
	(layers
		(0 "F.Cu" signal "TOP")
		(4 "In1.Cu" signal "L2GND")
		(6 "In2.Cu" signal "L3")
		(8 "In3.Cu" signal "L4GND")
		(10 "In4.Cu" signal "L5")
		(12 "In5.Cu" signal "L6GND")
		(14 "In6.Cu" signal "L7VCC")
		(16 "In7.Cu" signal "L8VCC")
		(18 "In8.Cu" signal "L9GND")
		(20 "In9.Cu" signal "L10")
		(22 "In10.Cu" signal "L11GND")
		(24 "In11.Cu" signal "L12")
		(26 "In12.Cu" signal "L13GND")
		(2 "B.Cu" signal "BOTTOM")
		(9 "F.Adhes" user "F.Adhesive")
		(11 "B.Adhes" user "B.Adhesive")
		(13 "F.Paste" user "Package Geometry/Pastemask Top")
		(15 "B.Paste" user "Package Geometry/Pastemask Bottom")
		(5 "F.SilkS" user "Ref Des/Silkscreen Top")
		(7 "B.SilkS" user "Ref Des/Silkscreen Bottom")
		(1 "F.Mask" user "Board Geometry/Soldermask Top")
		(3 "B.Mask" user "Board Geometry/Soldermask Bottom")
		(17 "Dwgs.User" user "User.Drawings")
		(19 "Cmts.User" user "User.Comments")
		(21 "Eco1.User" user "User.Eco1")
		(23 "Eco2.User" user "User.Eco2")
		(25 "Edge.Cuts" user "Board Geometry/Outline")
		(27 "Margin" user)
		(31 "F.CrtYd" user "Package Geometry/Place Bound Top")
		(29 "B.CrtYd" user "Package Geometry/Place Bound Bottom")
		(35 "F.Fab" user "Ref Des/Assembly Top")
		(33 "B.Fab" user "Ref Des/Assembly Bottom")
	)
	(footprint ""
		(layer "B.Cu")
		(at 29.699458 -132.876036 90)
		(property "Reference" "J9M1"
			(at 2.352548 37.991542 0)
			(unlocked yes)
			(layer "B.SilkS")
			(effects
				(font
					(size 0.7874 0.5842)
					(thickness 0.1524)
				)
				(justify left mirror)
			)
		)
		(property "Value" ""
			(at 0 0 90)
			(layer "B.Fab")
			(effects
				(font
					(size 1.27 1.27)
				)
				(justify mirror)
			)
		)
		(duplicate_pad_numbers_are_jumpers no)
		(pad "241" smd rect
			(at -4.59994 86.700106 270)
			(size 1.8034 0.508)
			(layers "B.Cu" "B.Mask" "B.Paste")
			(net "GND")
		)
		(pad "242" smd rect
			(at -4.59994 87.54999 270)
			(size 1.8034 0.508)
			(layers "B.Cu" "B.Mask" "B.Paste")
			(net "M_K_DQ<33>")
		)
		(pad "243" smd rect
			(at -4.59994 88.399874 270)
			(size 1.8034 0.508)
			(layers "B.Cu" "B.Mask" "B.Paste")
			(net "GND")
		)
		(pad "244" smd rect
			(at -4.59994 89.250012 270)
			(size 1.8034 0.508)
			(layers "B.Cu" "B.Mask" "B.Paste")
			(net "M_K_DQS_DN<4>")
		)
		(pad "245" smd rect
			(at -4.59994 90.099896 270)
			(size 1.8034 0.508)
			(layers "B.Cu" "B.Mask" "B.Paste")
			(net "M_K_DQS_DP<4>")
		)
		(pad "246" smd rect
			(at -4.59994 90.950034 270)
			(size 1.8034 0.508)
			(layers "B.Cu" "B.Mask" "B.Paste")
			(net "GND")
		)
		(pad "247" smd rect
			(at -4.59994 91.799918 270)
			(size 1.8034 0.508)
			(layers "B.Cu" "B.Mask" "B.Paste")
			(net "M_K_DQ<39>")
		)
		(pad "248" smd rect
			(at -4.59994 92.650056 270)
			(size 1.8034 0.508)
			(layers "B.Cu" "B.Mask" "B.Paste")
			(net "GND")
		)
		(pad "249" smd rect
			(at -4.59994 93.49994 270)
			(size 1.8034 0.508)
			(layers "B.Cu" "B.Mask" "B.Paste")
			(net "M_K_DQ<35>")
		)
		(pad "250" smd rect
			(at -4.59994 94.350078 270)
			(size 1.8034 0.508)
			(layers "B.Cu" "B.Mask" "B.Paste")
			(net "GND")
		)
		(pad "251" smd rect
			(at -4.59994 95.199962 270)
			(size 1.8034 0.508)
			(layers "B.Cu" "B.Mask" "B.Paste")
			(net "M_K_DQ<45>")
		)
		(pad "252" smd rect
			(at -4.59994 96.0501 270)
			(size 1.8034 0.508)
			(layers "B.Cu" "B.Mask" "B.Paste")
			(net "GND")
		)
		(pad "253" smd rect
			(at -4.59994 96.899984 270)
			(size 1.8034 0.508)
			(layers "B.Cu" "B.Mask" "B.Paste")
			(net "M_K_DQ<41>")
		)
		(pad "254" smd rect
			(at -4.59994 97.750122 270)
			(size 1.8034 0.508)
			(layers "B.Cu" "B.Mask" "B.Paste")
			(net "GND")
		)
		(pad "255" smd rect
			(at -4.59994 98.600006 270)
			(size 1.8034 0.508)
			(layers "B.Cu" "B.Mask" "B.Paste")
			(net "M_K_DQS_DN<5>")
		)
		(pad "256" smd rect
			(at -4.59994 99.44989 270)
			(size 1.8034 0.508)
			(layers "B.Cu" "B.Mask" "B.Paste")
			(net "M_K_DQS_DP<5>")
		)
		(pad "257" smd rect
			(at -4.59994 100.300028 270)
			(size 1.8034 0.508)
			(layers "B.Cu" "B.Mask" "B.Paste")
			(net "GND")
		)
		(pad "258" smd rect
			(at -4.59994 101.149912 270)
			(size 1.8034 0.508)
			(layers "B.Cu" "B.Mask" "B.Paste")
			(net "M_K_DQ<47>")
		)
		(pad "259" smd rect
			(at -4.59994 102.00005 270)
			(size 1.8034 0.508)
			(layers "B.Cu" "B.Mask" "B.Paste")
			(net "GND")
		)
		(pad "260" smd rect
			(at -4.59994 102.849934 270)
			(size 1.8034 0.508)
			(layers "B.Cu" "B.Mask" "B.Paste")
			(net "M_K_DQ<43>")
		)
		(pad "261" smd rect
			(at -4.59994 103.700072 270)
			(size 1.8034 0.508)
			(layers "B.Cu" "B.Mask" "B.Paste")
			(net "GND")
		)
		(pad "262" smd rect
			(at -4.59994 104.549956 270)
			(size 1.8034 0.508)
			(layers "B.Cu" "B.Mask" "B.Paste")
			(net "M_K_DQ<53>")
		)
		(pad "263" smd rect
			(at -4.59994 105.400094 270)
			(size 1.8034 0.508)
			(layers "B.Cu" "B.Mask" "B.Paste")
			(net "GND")
		)
		(pad "264" smd rect
			(at -4.59994 106.249978 270)
			(size 1.8034 0.508)
			(layers "B.Cu" "B.Mask" "B.Paste")
			(net "M_K_DQ<49>")
		)
		(pad "265" smd rect
			(at -4.59994 107.100116 270)
			(size 1.8034 0.508)
			(layers "B.Cu" "B.Mask" "B.Paste")
			(net "GND")
		)
		(pad "266" smd rect
			(at -4.59994 107.95 270)
			(size 1.8034 0.508)
			(layers "B.Cu" "B.Mask" "B.Paste")
			(net "M_K_DQS_DN<6>")
		)
		(pad "267" smd rect
			(at -4.59994 108.799884 270)
			(size 1.8034 0.508)
			(layers "B.Cu" "B.Mask" "B.Paste")
			(net "M_K_DQS_DP<6>")
		)
		(pad "268" smd rect
			(at -4.59994 109.650022 270)
			(size 1.8034 0.508)
			(layers "B.Cu" "B.Mask" "B.Paste")
			(net "GND")
		)
		(pad "269" smd rect
			(at -4.59994 110.499906 270)
			(size 1.8034 0.508)
			(layers "B.Cu" "B.Mask" "B.Paste")
			(net "M_K_DQ<55>")
		)
		(pad "270" smd rect
			(at -4.59994 111.350044 270)
			(size 1.8034 0.508)
			(layers "B.Cu" "B.Mask" "B.Paste")
			(net "GND")
		)
		(pad "271" smd rect
			(at -4.59994 112.199928 270)
			(size 1.8034 0.508)
			(layers "B.Cu" "B.Mask" "B.Paste")
			(net "M_K_DQ<51>")
		)
		(pad "272" smd rect
			(at -4.59994 113.050066 270)
			(size 1.8034 0.508)
			(layers "B.Cu" "B.Mask" "B.Paste")
			(net "GND")
		)
		(pad "273" smd rect
			(at -4.59994 113.89995 270)
			(size 1.8034 0.508)
			(layers "B.Cu" "B.Mask" "B.Paste")
			(net "M_K_DQ<61>")
		)
		(pad "274" smd rect
			(at -4.59994 114.750088 270)
			(size 1.8034 0.508)
			(layers "B.Cu" "B.Mask" "B.Paste")
			(net "GND")
		)
		(pad "275" smd rect
			(at -4.59994 115.599972 270)
			(size 1.8034 0.508)
			(layers "B.Cu" "B.Mask" "B.Paste")
			(net "M_K_DQ<57>")
		)
		(pad "276" smd rect
			(at -4.59994 116.45011 270)
			(size 1.8034 0.508)
			(layers "B.Cu" "B.Mask" "B.Paste")
			(net "GND")
		)
		(pad "277" smd rect
			(at -4.59994 117.299994 270)
			(size 1.8034 0.508)
			(layers "B.Cu" "B.Mask" "B.Paste")
			(net "M_K_DQS_DN<7>")
		)
		(pad "278" smd rect
			(at -4.59994 118.149878 270)
			(size 1.8034 0.508)
			(layers "B.Cu" "B.Mask" "B.Paste")
			(net "M_K_DQS_DP<7>")
		)
		(pad "279" smd rect
			(at -4.59994 119.000016 270)
			(size 1.8034 0.508)
			(layers "B.Cu" "B.Mask" "B.Paste")
			(net "GND")
		)
		(pad "280" smd rect
			(at -4.59994 119.8499 270)
			(size 1.8034 0.508)
			(layers "B.Cu" "B.Mask" "B.Paste")
			(net "M_K_DQ<63>")
		)
		(pad "281" smd rect
			(at -4.59994 120.700038 270)
			(size 1.8034 0.508)
			(layers "B.Cu" "B.Mask" "B.Paste")
			(net "GND")
		)
		(pad "282" smd rect
			(at -4.59994 121.549922 270)
			(size 1.8034 0.508)
			(layers "B.Cu" "B.Mask" "B.Paste")
			(net "M_K_DQ<59>")
		)
		(pad "283" smd rect
			(at -4.59994 122.40006 270)
			(size 1.8034 0.508)
			(layers "B.Cu" "B.Mask" "B.Paste")
			(net "GND")
		)
		(pad "284" smd rect
			(at -4.59994 123.249944 270)
			(size 1.8034 0.508)
			(layers "B.Cu" "B.Mask" "B.Paste")
			(net "PVPP_KLM")
		)
		(pad "285" smd rect
			(at -4.59994 124.100082 270)
			(size 1.8034 0.508)
			(layers "B.Cu" "B.Mask" "B.Paste")
			(net "SMB_DDR_KLM_VPP_SDA")
		)
		(pad "286" smd rect
			(at -4.59994 124.949966 270)
			(size 1.8034 0.508)
			(layers "B.Cu" "B.Mask" "B.Paste")
			(net "PVPP_KLM")
		)
		(pad "287" smd rect
			(at -4.59994 125.800104 270)
			(size 1.8034 0.508)
			(layers "B.Cu" "B.Mask" "B.Paste")
			(net "PVPP_KLM")
		)
		(pad "288" smd rect
			(at -4.59994 126.649988 270)
			(size 1.8034 0.508)
			(layers "B.Cu" "B.Mask" "B.Paste")
			(net "PVPP_KLM")
		)
	)
)
